(kicad_pcb
	(version 20260206)
	(generator "pcbnew")
	(generator_version "10.0")
	(general
		(thickness 1.6)
		(legacy_teardrops no)
	)
	(paper "A4")
	(title_block
		(title "01162023_DA0F0TEBIF0_F0T_Expander_BD_F_brd_V02_OCP.brd")
		(comment 1 "Grand Teton / footprints 384-389 of 9728")
	)
	(layers
		(0 "F.Cu" signal "TOP")
		(4 "In1.Cu" signal "GND")
		(6 "In2.Cu" signal "VCC")
		(8 "In3.Cu" signal "VCC1")
		(10 "In4.Cu" signal "GND1")
		(12 "In5.Cu" signal "IN1")
		(14 "In6.Cu" signal "GND2")
		(16 "In7.Cu" signal "IN2")
		(18 "In8.Cu" signal "GND3")
		(20 "In9.Cu" signal "IN3")
		(22 "In10.Cu" signal "GND4")
		(24 "In11.Cu" signal "IN4")
		(26 "In12.Cu" signal "GND5")
		(28 "In13.Cu" signal "IN5")
		(30 "In14.Cu" signal "GND6")
		(32 "In15.Cu" signal "IN6")
		(34 "In16.Cu" signal "GND7")
		(2 "B.Cu" signal "BOTTOM")
		(9 "F.Adhes" user "F.Adhesive")
		(11 "B.Adhes" user "B.Adhesive")
		(13 "F.Paste" user "Package Geometry/Pastemask Top")
		(15 "B.Paste" user "Package Geometry/Pastemask Bottom")
		(5 "F.SilkS" user "Ref Des/Silkscreen Top")
		(7 "B.SilkS" user "Ref Des/Silkscreen Bottom")
		(1 "F.Mask" user "Board Geometry/Soldermask Top")
		(3 "B.Mask" user "Board Geometry/Soldermask Bottom")
		(17 "Dwgs.User" user "User.Drawings")
		(19 "Cmts.User" user "User.Comments")
		(21 "Eco1.User" user "User.Eco1")
		(23 "Eco2.User" user "User.Eco2")
		(25 "Edge.Cuts" user "Board Geometry/Outline")
		(27 "Margin" user)
		(31 "F.CrtYd" user "Package Geometry/Place Bound Top")
		(29 "B.CrtYd" user "Package Geometry/Place Bound Bottom")
		(35 "F.Fab" user "Ref Des/Assembly Top")
		(33 "B.Fab" user "Ref Des/Assembly Bottom")
	)
	(footprint ""
		(layer "F.Cu")
		(at 238.324898 -85.151468 90)
		(property "Reference" "R1017"
			(at 0 0 90)
			(layer "F.SilkS")
			(hide yes)
			(effects
				(font
					(size 1.27 1.27)
				)
			)
		)
		(property "Value" ""
			(at 0 0 90)
			(layer "F.Fab")
			(effects
				(font
					(size 1.27 1.27)
				)
			)
		)
		(duplicate_pad_numbers_are_jumpers no)
		(fp_line
			(start -0.7874 -0.4064)
			(end -0.020066 -0.4064)
			(stroke
				(width 0.1524)
				(type default)
			)
			(layer "F.SilkS")
		)
		(fp_line
			(start 0.7874 0.4064)
			(end 0.001524 0.4064)
			(stroke
				(width 0.1524)
				(type default)
			)
			(layer "F.SilkS")
		)
		(fp_line
			(start -0.12065 -0.305054)
			(end -0.12065 -0.2794)
			(stroke
				(width 0.1)
				(type default)
			)
			(layer "F.Fab")
		)
		(fp_line
			(start -0.67945 -0.305054)
			(end -0.12065 -0.305054)
			(stroke
				(width 0.1)
				(type default)
			)
			(layer "F.Fab")
		)
		(fp_line
			(start 0.67945 -0.3048)
			(end 0.67945 0.3048)
			(stroke
				(width 0.1)
				(type default)
			)
			(layer "F.Fab")
		)
		(fp_line
			(start 0.12065 -0.3048)
			(end 0.67945 -0.3048)
			(stroke
				(width 0.1)
				(type default)
			)
			(layer "F.Fab")
		)
		(fp_line
			(start 0.12065 -0.2794)
			(end 0.12065 -0.3048)
			(stroke
				(width 0.1)
				(type default)
			)
			(layer "F.Fab")
		)
		(fp_line
			(start -0.12065 -0.2794)
			(end 0.12065 -0.2794)
			(stroke
				(width 0.1)
				(type default)
			)
			(layer "F.Fab")
		)
		(fp_line
			(start 0.120396 0.2794)
			(end -0.12065 0.2794)
			(stroke
				(width 0.1)
				(type default)
			)
			(layer "F.Fab")
		)
		(fp_line
			(start -0.12065 0.2794)
			(end -0.12065 0.3048)
			(stroke
				(width 0.1)
				(type default)
			)
			(layer "F.Fab")
		)
		(fp_line
			(start 0.67945 0.3048)
			(end 0.120396 0.3048)
			(stroke
				(width 0.1)
				(type default)
			)
			(layer "F.Fab")
		)
		(fp_line
			(start 0.120396 0.3048)
			(end 0.120396 0.2794)
			(stroke
				(width 0.1)
				(type default)
			)
			(layer "F.Fab")
		)
		(fp_line
			(start -0.12065 0.3048)
			(end -0.67945 0.3048)
			(stroke
				(width 0.1)
				(type default)
			)
			(layer "F.Fab")
		)
		(fp_line
			(start -0.67945 0.3048)
			(end -0.67945 -0.305054)
			(stroke
				(width 0.1)
				(type default)
			)
			(layer "F.Fab")
		)
		(pad "1" smd rect
			(at -0.40005 0 270)
			(size 0.4572 0.508)
			(layers "F.Cu" "F.Mask" "F.Paste")
			(net "USB2_FT4232_CLI_R_DN")
		)
		(pad "2" smd rect
			(at 0.40005 0 270)
			(size 0.4572 0.508)
			(layers "F.Cu" "F.Mask" "F.Paste")
			(net "USB2_FT4232_CLI_DN")
		)
	)
	(footprint ""
		(layer "F.Cu")
		(at 206.96809 -289.230816 90)
		(property "Reference" "R3939"
			(at 0 0 90)
			(layer "F.SilkS")
			(hide yes)
			(effects
				(font
					(size 1.27 1.27)
				)
			)
		)
		(property "Value" ""
			(at 0 0 90)
			(layer "F.Fab")
			(effects
				(font
					(size 1.27 1.27)
				)
			)
		)
		(duplicate_pad_numbers_are_jumpers no)
		(fp_line
			(start 0.7874 -0.4064)
			(end 0.7874 0.4064)
			(stroke
				(width 0.1524)
				(type default)
			)
			(layer "F.SilkS")
		)
		(fp_line
			(start -0.7874 -0.4064)
			(end 0.7874 -0.4064)
			(stroke
				(width 0.1524)
				(type default)
			)
			(layer "F.SilkS")
		)
		(fp_line
			(start 0.7874 0.4064)
			(end -0.7874 0.4064)
			(stroke
				(width 0.1524)
				(type default)
			)
			(layer "F.SilkS")
		)
		(fp_line
			(start -0.7874 0.4064)
			(end -0.7874 -0.4064)
			(stroke
				(width 0.1524)
				(type default)
			)
			(layer "F.SilkS")
		)
		(fp_line
			(start -0.12065 -0.305054)
			(end -0.12065 -0.2794)
			(stroke
				(width 0.1)
				(type default)
			)
			(layer "F.Fab")
		)
		(fp_line
			(start -0.67945 -0.305054)
			(end -0.12065 -0.305054)
			(stroke
				(width 0.1)
				(type default)
			)
			(layer "F.Fab")
		)
		(fp_line
			(start 0.67945 -0.3048)
			(end 0.67945 0.3048)
			(stroke
				(width 0.1)
				(type default)
			)
			(layer "F.Fab")
		)
		(fp_line
			(start 0.12065 -0.3048)
			(end 0.67945 -0.3048)
			(stroke
				(width 0.1)
				(type default)
			)
			(layer "F.Fab")
		)
		(fp_line
			(start 0.12065 -0.2794)
			(end 0.12065 -0.3048)
			(stroke
				(width 0.1)
				(type default)
			)
			(layer "F.Fab")
		)
		(fp_line
			(start -0.12065 -0.2794)
			(end 0.12065 -0.2794)
			(stroke
				(width 0.1)
				(type default)
			)
			(layer "F.Fab")
		)
		(fp_line
			(start 0.120396 0.2794)
			(end -0.12065 0.2794)
			(stroke
				(width 0.1)
				(type default)
			)
			(layer "F.Fab")
		)
		(fp_line
			(start -0.12065 0.2794)
			(end -0.12065 0.3048)
			(stroke
				(width 0.1)
				(type default)
			)
			(layer "F.Fab")
		)
		(fp_line
			(start 0.67945 0.3048)
			(end 0.120396 0.3048)
			(stroke
				(width 0.1)
				(type default)
			)
			(layer "F.Fab")
		)
		(fp_line
			(start 0.120396 0.3048)
			(end 0.120396 0.2794)
			(stroke
				(width 0.1)
				(type default)
			)
			(layer "F.Fab")
		)
		(fp_line
			(start -0.12065 0.3048)
			(end -0.67945 0.3048)
			(stroke
				(width 0.1)
				(type default)
			)
			(layer "F.Fab")
		)
		(fp_line
			(start -0.67945 0.3048)
			(end -0.67945 -0.305054)
			(stroke
				(width 0.1)
				(type default)
			)
			(layer "F.Fab")
		)
		(pad "1" smd circle
			(at -0.40005 0 90)
			(size 0 0)
			(layers "F.Cu" "F.Mask" "F.Paste")
			(net "SMB_PEX1_FPGA_SCL")
		)
		(pad "2" smd circle
			(at 0.40005 0 90)
			(size 0 0)
			(layers "F.Cu" "F.Mask" "F.Paste")
			(net "SMB_PEX1_HOST_LS_SCL")
		)
	)
	(footprint ""
		(layer "F.Cu")
		(at 381.587756 -288.419032)
		(property "Reference" "C3577"
			(at 0 0 0)
			(layer "F.SilkS")
			(hide yes)
			(effects
				(font
					(size 1.27 1.27)
				)
			)
		)
		(property "Value" ""
			(at 0 0 0)
			(layer "F.Fab")
			(effects
				(font
					(size 1.27 1.27)
				)
			)
		)
		(duplicate_pad_numbers_are_jumpers no)
		(fp_line
			(start -1.2954 -0.5842)
			(end 1.2954 -0.5842)
			(stroke
				(width 0.1524)
				(type default)
			)
			(layer "F.SilkS")
		)
		(fp_line
			(start -1.2954 0.5842)
			(end -1.2954 -0.5842)
			(stroke
				(width 0.1524)
				(type default)
			)
			(layer "F.SilkS")
		)
		(fp_line
			(start 1.2954 -0.5842)
			(end 1.2954 0.5842)
			(stroke
				(width 0.1524)
				(type default)
			)
			(layer "F.SilkS")
		)
		(fp_line
			(start 1.2954 0.5842)
			(end -1.2954 0.5842)
			(stroke
				(width 0.1524)
				(type default)
			)
			(layer "F.SilkS")
		)
		(fp_line
			(start -1.1938 -0.4064)
			(end -0.8636 -0.4064)
			(stroke
				(width 0.1)
				(type default)
			)
			(layer "F.Fab")
		)
		(fp_line
			(start -1.1938 0.4064)
			(end -1.1938 -0.4064)
			(stroke
				(width 0.1)
				(type default)
			)
			(layer "F.Fab")
		)
		(fp_line
			(start -0.8636 -0.4572)
			(end 0.8636 -0.4572)
			(stroke
				(width 0.1)
				(type default)
			)
			(layer "F.Fab")
		)
		(fp_line
			(start -0.8636 -0.4064)
			(end -0.8636 -0.4572)
			(stroke
				(width 0.1)
				(type default)
			)
			(layer "F.Fab")
		)
		(fp_line
			(start -0.8636 0.4064)
			(end -1.1938 0.4064)
			(stroke
				(width 0.1)
				(type default)
			)
			(layer "F.Fab")
		)
		(fp_line
			(start -0.8636 0.4572)
			(end -0.8636 0.4064)
			(stroke
				(width 0.1)
				(type default)
			)
			(layer "F.Fab")
		)
		(fp_line
			(start 0.8636 -0.4572)
			(end 0.8636 -0.4064)
			(stroke
				(width 0.1)
				(type default)
			)
			(layer "F.Fab")
		)
		(fp_line
			(start 0.8636 -0.4064)
			(end 1.1938 -0.4064)
			(stroke
				(width 0.1)
				(type default)
			)
			(layer "F.Fab")
		)
		(fp_line
			(start 0.8636 0.4064)
			(end 0.8636 0.4572)
			(stroke
				(width 0.1)
				(type default)
			)
			(layer "F.Fab")
		)
		(fp_line
			(start 0.8636 0.4572)
			(end -0.8636 0.4572)
			(stroke
				(width 0.1)
				(type default)
			)
			(layer "F.Fab")
		)
		(fp_line
			(start 1.1938 -0.4064)
			(end 1.1938 0.4064)
			(stroke
				(width 0.1)
				(type default)
			)
			(layer "F.Fab")
		)
		(fp_line
			(start 1.1938 0.4064)
			(end 0.8636 0.4064)
			(stroke
				(width 0.1)
				(type default)
			)
			(layer "F.Fab")
		)
		(pad "1" smd rect
			(at -0.7366 0 270)
			(size 0.7112 0.8128)
			(layers "F.Cu" "F.Mask" "F.Paste")
			(net "PCEPLL6_VDDA18_PEX3")
		)
		(pad "2" smd rect
			(at 0.7366 0 270)
			(size 0.7112 0.8128)
			(layers "F.Cu" "F.Mask" "F.Paste")
			(net "GND")
		)
	)
	(footprint ""
		(layer "F.Cu")
		(at 134.366 -282.421584 -90)
		(property "Reference" "PC113"
			(at 0 0 270)
			(layer "F.SilkS")
			(hide yes)
			(effects
				(font
					(size 1.27 1.27)
				)
			)
		)
		(property "Value" ""
			(at 0 0 270)
			(layer "F.Fab")
			(effects
				(font
					(size 1.27 1.27)
				)
			)
		)
		(duplicate_pad_numbers_are_jumpers no)
		(fp_line
			(start -0.7874 0.4064)
			(end -0.7874 -0.4064)
			(stroke
				(width 0.1524)
				(type default)
			)
			(layer "F.SilkS")
		)
		(fp_line
			(start 0.7874 0.4064)
			(end -0.7874 0.4064)
			(stroke
				(width 0.1524)
				(type default)
			)
			(layer "F.SilkS")
		)
		(fp_line
			(start -0.7874 -0.4064)
			(end 0.7874 -0.4064)
			(stroke
				(width 0.1524)
				(type default)
			)
			(layer "F.SilkS")
		)
		(fp_line
			(start 0.7874 -0.4064)
			(end 0.7874 0.4064)
			(stroke
				(width 0.1524)
				(type default)
			)
			(layer "F.SilkS")
		)
		(fp_line
			(start -0.67945 0.3048)
			(end -0.67945 -0.305054)
			(stroke
				(width 0.1)
				(type default)
			)
			(layer "F.Fab")
		)
		(fp_line
			(start -0.12065 0.3048)
			(end -0.67945 0.3048)
			(stroke
				(width 0.1)
				(type default)
			)
			(layer "F.Fab")
		)
		(fp_line
			(start 0.120396 0.3048)
			(end 0.120396 0.2794)
			(stroke
				(width 0.1)
				(type default)
			)
			(layer "F.Fab")
		)
		(fp_line
			(start 0.67945 0.3048)
			(end 0.120396 0.3048)
			(stroke
				(width 0.1)
				(type default)
			)
			(layer "F.Fab")
		)
		(fp_line
			(start -0.12065 0.2794)
			(end -0.12065 0.3048)
			(stroke
				(width 0.1)
				(type default)
			)
			(layer "F.Fab")
		)
		(fp_line
			(start 0.120396 0.2794)
			(end -0.12065 0.2794)
			(stroke
				(width 0.1)
				(type default)
			)
			(layer "F.Fab")
		)
		(fp_line
			(start -0.12065 -0.2794)
			(end 0.12065 -0.2794)
			(stroke
				(width 0.1)
				(type default)
			)
			(layer "F.Fab")
		)
		(fp_line
			(start 0.12065 -0.2794)
			(end 0.12065 -0.3048)
			(stroke
				(width 0.1)
				(type default)
			)
			(layer "F.Fab")
		)
		(fp_line
			(start 0.12065 -0.3048)
			(end 0.67945 -0.3048)
			(stroke
				(width 0.1)
				(type default)
			)
			(layer "F.Fab")
		)
		(fp_line
			(start 0.67945 -0.3048)
			(end 0.67945 0.3048)
			(stroke
				(width 0.1)
				(type default)
			)
			(layer "F.Fab")
		)
		(fp_line
			(start -0.67945 -0.305054)
			(end -0.12065 -0.305054)
			(stroke
				(width 0.1)
				(type default)
			)
			(layer "F.Fab")
		)
		(fp_line
			(start -0.12065 -0.305054)
			(end -0.12065 -0.2794)
			(stroke
				(width 0.1)
				(type default)
			)
			(layer "F.Fab")
		)
		(pad "1" smd circle
			(at -0.40005 0 270)
			(size 0 0)
			(layers "F.Cu" "F.Mask" "F.Paste")
			(net "P0V8_PEX1_VCC2")
		)
		(pad "2" smd circle
			(at 0.40005 0 270)
			(size 0 0)
			(layers "F.Cu" "F.Mask" "F.Paste")
			(net "GND")
		)
	)
	(footprint ""
		(layer "F.Cu")
		(at 6.119114 -59.574684 90)
		(property "Reference" "PC541"
			(at 0 0 90)
			(layer "F.SilkS")
			(hide yes)
			(effects
				(font
					(size 1.27 1.27)
				)
			)
		)
		(property "Value" ""
			(at 0 0 90)
			(layer "F.Fab")
			(effects
				(font
					(size 1.27 1.27)
				)
			)
		)
		(duplicate_pad_numbers_are_jumpers no)
		(fp_line
			(start 0.7874 -0.4064)
			(end 0.7874 0.4064)
			(stroke
				(width 0.1524)
				(type default)
			)
			(layer "F.SilkS")
		)
		(fp_line
			(start -0.7874 -0.4064)
			(end 0.7874 -0.4064)
			(stroke
				(width 0.1524)
				(type default)
			)
			(layer "F.SilkS")
		)
		(fp_line
			(start 0.7874 0.4064)
			(end -0.7874 0.4064)
			(stroke
				(width 0.1524)
				(type default)
			)
			(layer "F.SilkS")
		)
		(fp_line
			(start -0.7874 0.4064)
			(end -0.7874 -0.4064)
			(stroke
				(width 0.1524)
				(type default)
			)
			(layer "F.SilkS")
		)
		(fp_line
			(start -0.12065 -0.305054)
			(end -0.12065 -0.2794)
			(stroke
				(width 0.1)
				(type default)
			)
			(layer "F.Fab")
		)
		(fp_line
			(start -0.67945 -0.305054)
			(end -0.12065 -0.305054)
			(stroke
				(width 0.1)
				(type default)
			)
			(layer "F.Fab")
		)
		(fp_line
			(start 0.67945 -0.3048)
			(end 0.67945 0.3048)
			(stroke
				(width 0.1)
				(type default)
			)
			(layer "F.Fab")
		)
		(fp_line
			(start 0.12065 -0.3048)
			(end 0.67945 -0.3048)
			(stroke
				(width 0.1)
				(type default)
			)
			(layer "F.Fab")
		)
		(fp_line
			(start 0.12065 -0.2794)
			(end 0.12065 -0.3048)
			(stroke
				(width 0.1)
				(type default)
			)
			(layer "F.Fab")
		)
		(fp_line
			(start -0.12065 -0.2794)
			(end 0.12065 -0.2794)
			(stroke
				(width 0.1)
				(type default)
			)
			(layer "F.Fab")
		)
		(fp_line
			(start 0.120396 0.2794)
			(end -0.12065 0.2794)
			(stroke
				(width 0.1)
				(type default)
			)
			(layer "F.Fab")
		)
		(fp_line
			(start -0.12065 0.2794)
			(end -0.12065 0.3048)
			(stroke
				(width 0.1)
				(type default)
			)
			(layer "F.Fab")
		)
		(fp_line
			(start 0.67945 0.3048)
			(end 0.120396 0.3048)
			(stroke
				(width 0.1)
				(type default)
			)
			(layer "F.Fab")
		)
		(fp_line
			(start 0.120396 0.3048)
			(end 0.120396 0.2794)
			(stroke
				(width 0.1)
				(type default)
			)
			(layer "F.Fab")
		)
		(fp_line
			(start -0.12065 0.3048)
			(end -0.67945 0.3048)
			(stroke
				(width 0.1)
				(type default)
			)
			(layer "F.Fab")
		)
		(fp_line
			(start -0.67945 0.3048)
			(end -0.67945 -0.305054)
			(stroke
				(width 0.1)
				(type default)
			)
			(layer "F.Fab")
		)
		(pad "1" smd circle
			(at -0.40005 0 90)
			(size 0 0)
			(layers "F.Cu" "F.Mask" "F.Paste")
			(net "P5V_AUX")
		)
		(pad "2" smd circle
			(at 0.40005 0 90)
			(size 0 0)
			(layers "F.Cu" "F.Mask" "F.Paste")
			(net "GND")
		)
	)
	(footprint ""
		(layer "F.Cu")
		(at 248.94159 -378.393706 -90)
		(property "Reference" "PR6602"
			(at 0 0 270)
			(layer "F.SilkS")
			(hide yes)
			(effects
				(font
					(size 1.27 1.27)
				)
			)
		)
		(property "Value" ""
			(at 0 0 270)
			(layer "F.Fab")
			(effects
				(font
					(size 1.27 1.27)
				)
			)
		)
		(duplicate_pad_numbers_are_jumpers no)
		(fp_line
			(start -3.9878 3.5814)
			(end -3.9878 -3.5814)
			(stroke
				(width 0.1524)
				(type default)
			)
			(layer "F.SilkS")
		)
		(fp_line
			(start 3.9878 3.5814)
			(end -3.9878 3.5814)
			(stroke
				(width 0.1524)
				(type default)
			)
			(layer "F.SilkS")
		)
		(fp_line
			(start -3.9878 -3.5814)
			(end 3.9878 -3.5814)
			(stroke
				(width 0.1524)
				(type default)
			)
			(layer "F.SilkS")
		)
		(fp_line
			(start 3.9878 -3.5814)
			(end 3.9878 3.5814)
			(stroke
				(width 0.1524)
				(type default)
			)
			(layer "F.SilkS")
		)
		(fp_line
			(start -3.5306 3.353054)
			(end -3.5306 -3.353054)
			(stroke
				(width 0.1)
				(type default)
			)
			(layer "F.Fab")
		)
		(fp_line
			(start 3.5306 3.353054)
			(end -3.5306 3.353054)
			(stroke
				(width 0.1)
				(type default)
			)
			(layer "F.Fab")
		)
		(fp_line
			(start -3.5306 -3.353054)
			(end 3.5306 -3.353054)
			(stroke
				(width 0.1)
				(type default)
			)
			(layer "F.Fab")
		)
		(fp_line
			(start 3.5306 -3.353054)
			(end 3.5306 3.353054)
			(stroke
				(width 0.1)
				(type default)
			)
			(layer "F.Fab")
		)
		(pad "1A" smd rect
			(at -2.249932 0 90)
			(size 3.2004 6.858)
			(layers "F.Cu" "F.Mask" "F.Paste")
			(net "P12V_STBY")
		)
		(pad "1B" smd rect
			(at -0.776732 0 270)
			(size 0.254 0.508)
			(layers "F.Cu" "F.Mask" "F.Paste")
			(net "P12V_HSC_SENSE2_R1_P")
		)
		(pad "2A" smd rect
			(at 2.249932 0 90)
			(size 3.2004 6.858)
			(layers "F.Cu" "F.Mask" "F.Paste")
			(net "P12V_STBY_R2")
		)
		(pad "2B" smd rect
			(at 0.776732 0 270)
			(size 0.254 0.508)
			(layers "F.Cu" "F.Mask" "F.Paste")
			(net "P12V_HSC_SENSE2_R1_N")
		)
	)
)
